(kicad_pcb
	(version 20260206)
	(generator "pcbnew")
	(generator_version "10.0")
	(general
		(thickness 1.6)
		(legacy_teardrops no)
	)
	(paper "A4")
	(title_block
		(title "04192023_DAF0TMB3IC0_F0TG_MB_C_brd_V02_OCP.brd")
		(comment 1 "Grand Teton / footprints 6179-6185 of 8354")
	)
	(layers
		(0 "F.Cu" signal "TOP")
		(4 "In1.Cu" signal "GND")
		(6 "In2.Cu" signal "IN1")
		(8 "In3.Cu" signal "GND1")
		(10 "In4.Cu" signal "IN2")
		(12 "In5.Cu" signal "GND2")
		(14 "In6.Cu" signal "IN3")
		(16 "In7.Cu" signal "GND3")
		(18 "In8.Cu" signal "VCC")
		(20 "In9.Cu" signal "VCC1")
		(22 "In10.Cu" signal "GND4")
		(24 "In11.Cu" signal "IN4")
		(26 "In12.Cu" signal "GND5")
		(28 "In13.Cu" signal "IN5")
		(30 "In14.Cu" signal "GND6")
		(32 "In15.Cu" signal "IN6")
		(34 "In16.Cu" signal "GND7")
		(2 "B.Cu" signal "BOTTOM")
		(9 "F.Adhes" user "F.Adhesive")
		(11 "B.Adhes" user "B.Adhesive")
		(13 "F.Paste" user "Package Geometry/Pastemask Top")
		(15 "B.Paste" user "Package Geometry/Pastemask Bottom")
		(5 "F.SilkS" user "Ref Des/Silkscreen Top")
		(7 "B.SilkS" user "Ref Des/Silkscreen Bottom")
		(1 "F.Mask" user "Board Geometry/Soldermask Top")
		(3 "B.Mask" user "Board Geometry/Soldermask Bottom")
		(17 "Dwgs.User" user "User.Drawings")
		(19 "Cmts.User" user "User.Comments")
		(21 "Eco1.User" user "User.Eco1")
		(23 "Eco2.User" user "User.Eco2")
		(25 "Edge.Cuts" user "Board Geometry/Outline")
		(27 "Margin" user)
		(31 "F.CrtYd" user "Package Geometry/Place Bound Top")
		(29 "B.CrtYd" user "Package Geometry/Place Bound Bottom")
		(35 "F.Fab" user "Ref Des/Assembly Top")
		(33 "B.Fab" user "Ref Des/Assembly Bottom")
	)
	(footprint ""
		(layer "B.Cu")
		(at 154.348434 -199.234552 -90)
		(property "Reference" "C230"
			(at 0 0 90)
			(layer "B.SilkS")
			(hide yes)
			(effects
				(font
					(size 1.27 1.27)
				)
				(justify mirror)
			)
		)
		(property "Value" ""
			(at 0 0 90)
			(layer "B.Fab")
			(effects
				(font
					(size 1.27 1.27)
				)
				(justify mirror)
			)
		)
		(duplicate_pad_numbers_are_jumpers no)
		(fp_line
			(start -0.7874 0.4064)
			(end 0.7874 0.4064)
			(stroke
				(width 0.1524)
				(type default)
			)
			(layer "B.SilkS")
		)
		(fp_line
			(start 0.7874 0.4064)
			(end 0.7874 -0.4064)
			(stroke
				(width 0.1524)
				(type default)
			)
			(layer "B.SilkS")
		)
		(fp_line
			(start -0.7874 -0.4064)
			(end -0.7874 0.4064)
			(stroke
				(width 0.1524)
				(type default)
			)
			(layer "B.SilkS")
		)
		(fp_line
			(start 0.7874 -0.4064)
			(end -0.7874 -0.4064)
			(stroke
				(width 0.1524)
				(type default)
			)
			(layer "B.SilkS")
		)
		(fp_line
			(start -0.67945 0.3048)
			(end -0.120396 0.3048)
			(stroke
				(width 0.1)
				(type default)
			)
			(layer "B.Fab")
		)
		(fp_line
			(start -0.120396 0.3048)
			(end -0.120396 0.2794)
			(stroke
				(width 0.1)
				(type default)
			)
			(layer "B.Fab")
		)
		(fp_line
			(start 0.12065 0.3048)
			(end 0.67945 0.3048)
			(stroke
				(width 0.1)
				(type default)
			)
			(layer "B.Fab")
		)
		(fp_line
			(start 0.67945 0.3048)
			(end 0.67945 -0.305054)
			(stroke
				(width 0.1)
				(type default)
			)
			(layer "B.Fab")
		)
		(fp_line
			(start -0.120396 0.2794)
			(end 0.12065 0.2794)
			(stroke
				(width 0.1)
				(type default)
			)
			(layer "B.Fab")
		)
		(fp_line
			(start 0.12065 0.2794)
			(end 0.12065 0.3048)
			(stroke
				(width 0.1)
				(type default)
			)
			(layer "B.Fab")
		)
		(fp_line
			(start -0.12065 -0.2794)
			(end -0.12065 -0.3048)
			(stroke
				(width 0.1)
				(type default)
			)
			(layer "B.Fab")
		)
		(fp_line
			(start 0.12065 -0.2794)
			(end -0.12065 -0.2794)
			(stroke
				(width 0.1)
				(type default)
			)
			(layer "B.Fab")
		)
		(fp_line
			(start -0.67945 -0.3048)
			(end -0.67945 0.3048)
			(stroke
				(width 0.1)
				(type default)
			)
			(layer "B.Fab")
		)
		(fp_line
			(start -0.12065 -0.3048)
			(end -0.67945 -0.3048)
			(stroke
				(width 0.1)
				(type default)
			)
			(layer "B.Fab")
		)
		(fp_line
			(start 0.12065 -0.305054)
			(end 0.12065 -0.2794)
			(stroke
				(width 0.1)
				(type default)
			)
			(layer "B.Fab")
		)
		(fp_line
			(start 0.67945 -0.305054)
			(end 0.12065 -0.305054)
			(stroke
				(width 0.1)
				(type default)
			)
			(layer "B.Fab")
		)
		(pad "1" smd circle
			(at 0.40005 0 90)
			(size 0 0)
			(layers "B.Cu" "B.Mask" "B.Paste")
			(net "JTAG_CPU1_TDO")
		)
		(pad "2" smd circle
			(at -0.40005 0 90)
			(size 0 0)
			(layers "B.Cu" "B.Mask" "B.Paste")
			(net "GND")
		)
	)
	(footprint ""
		(layer "B.Cu")
		(at 434.797454 -191.20231 180)
		(property "Reference" "R300"
			(at 0 0 0)
			(layer "B.SilkS")
			(hide yes)
			(effects
				(font
					(size 1.27 1.27)
				)
				(justify mirror)
			)
		)
		(property "Value" ""
			(at 0 0 0)
			(layer "B.Fab")
			(effects
				(font
					(size 1.27 1.27)
				)
				(justify mirror)
			)
		)
		(duplicate_pad_numbers_are_jumpers no)
		(fp_line
			(start 0.7874 0.4064)
			(end 0.7874 -0.4064)
			(stroke
				(width 0.1524)
				(type default)
			)
			(layer "B.SilkS")
		)
		(fp_line
			(start 0.7874 -0.4064)
			(end -0.7874 -0.4064)
			(stroke
				(width 0.1524)
				(type default)
			)
			(layer "B.SilkS")
		)
		(fp_line
			(start -0.7874 0.4064)
			(end 0.7874 0.4064)
			(stroke
				(width 0.1524)
				(type default)
			)
			(layer "B.SilkS")
		)
		(fp_line
			(start -0.7874 -0.4064)
			(end -0.7874 0.4064)
			(stroke
				(width 0.1524)
				(type default)
			)
			(layer "B.SilkS")
		)
		(fp_line
			(start 0.67945 0.3048)
			(end 0.67945 -0.305054)
			(stroke
				(width 0.1)
				(type default)
			)
			(layer "B.Fab")
		)
		(fp_line
			(start 0.67945 -0.305054)
			(end 0.12065 -0.305054)
			(stroke
				(width 0.1)
				(type default)
			)
			(layer "B.Fab")
		)
		(fp_line
			(start 0.12065 0.3048)
			(end 0.67945 0.3048)
			(stroke
				(width 0.1)
				(type default)
			)
			(layer "B.Fab")
		)
		(fp_line
			(start 0.12065 0.2794)
			(end 0.12065 0.3048)
			(stroke
				(width 0.1)
				(type default)
			)
			(layer "B.Fab")
		)
		(fp_line
			(start 0.12065 -0.2794)
			(end -0.12065 -0.2794)
			(stroke
				(width 0.1)
				(type default)
			)
			(layer "B.Fab")
		)
		(fp_line
			(start 0.12065 -0.305054)
			(end 0.12065 -0.2794)
			(stroke
				(width 0.1)
				(type default)
			)
			(layer "B.Fab")
		)
		(fp_line
			(start -0.120396 0.3048)
			(end -0.120396 0.2794)
			(stroke
				(width 0.1)
				(type default)
			)
			(layer "B.Fab")
		)
		(fp_line
			(start -0.120396 0.2794)
			(end 0.12065 0.2794)
			(stroke
				(width 0.1)
				(type default)
			)
			(layer "B.Fab")
		)
		(fp_line
			(start -0.12065 -0.2794)
			(end -0.12065 -0.3048)
			(stroke
				(width 0.1)
				(type default)
			)
			(layer "B.Fab")
		)
		(fp_line
			(start -0.12065 -0.3048)
			(end -0.67945 -0.3048)
			(stroke
				(width 0.1)
				(type default)
			)
			(layer "B.Fab")
		)
		(fp_line
			(start -0.67945 0.3048)
			(end -0.120396 0.3048)
			(stroke
				(width 0.1)
				(type default)
			)
			(layer "B.Fab")
		)
		(fp_line
			(start -0.67945 -0.3048)
			(end -0.67945 0.3048)
			(stroke
				(width 0.1)
				(type default)
			)
			(layer "B.Fab")
		)
		(pad "1" smd circle
			(at 0.40005 0)
			(size 0 0)
			(layers "B.Cu" "B.Mask" "B.Paste")
			(net "PWRGD_CHJ_CPU0_DIMM")
		)
		(pad "2" smd circle
			(at -0.40005 0)
			(size 0 0)
			(layers "B.Cu" "B.Mask" "B.Paste")
			(net "PWRGD_CHGL_CPU0")
		)
	)
	(footprint ""
		(layer "B.Cu")
		(at 216.916 -336.169 -90)
		(property "Reference" "R6738"
			(at 0 0 90)
			(layer "B.SilkS")
			(hide yes)
			(effects
				(font
					(size 1.27 1.27)
				)
				(justify mirror)
			)
		)
		(property "Value" ""
			(at 0 0 90)
			(layer "B.Fab")
			(effects
				(font
					(size 1.27 1.27)
				)
				(justify mirror)
			)
		)
		(duplicate_pad_numbers_are_jumpers no)
		(fp_line
			(start -0.32512 0.175006)
			(end 0.32512 0.175006)
			(stroke
				(width 0.1)
				(type default)
			)
			(layer "B.Fab")
		)
		(fp_line
			(start 0.32512 0.175006)
			(end 0.32512 -0.175006)
			(stroke
				(width 0.1)
				(type default)
			)
			(layer "B.Fab")
		)
		(fp_line
			(start -0.32512 -0.175006)
			(end -0.32512 0.175006)
			(stroke
				(width 0.1)
				(type default)
			)
			(layer "B.Fab")
		)
		(fp_line
			(start 0.32512 -0.175006)
			(end -0.32512 -0.175006)
			(stroke
				(width 0.1)
				(type default)
			)
			(layer "B.Fab")
		)
		(pad "1" smd rect
			(at 0.2667 0 90)
			(size 0.3048 0.381)
			(layers "B.Cu" "B.Mask" "B.Paste")
			(net "P1V8_CPU1_RT_1D")
		)
		(pad "2" smd rect
			(at -0.2667 0 270)
			(size 0.3048 0.381)
			(layers "B.Cu" "B.Mask" "B.Paste")
			(net "SMB_RT_CPU1_P1_R_SDA")
		)
	)
	(footprint ""
		(layer "B.Cu")
		(at 329.889358 -401.624546 180)
		(property "Reference" "R1011"
			(at 0 0 0)
			(layer "B.SilkS")
			(hide yes)
			(effects
				(font
					(size 1.27 1.27)
				)
				(justify mirror)
			)
		)
		(property "Value" ""
			(at 0 0 0)
			(layer "B.Fab")
			(effects
				(font
					(size 1.27 1.27)
				)
				(justify mirror)
			)
		)
		(duplicate_pad_numbers_are_jumpers no)
		(fp_line
			(start 1.2954 0.5842)
			(end 1.2954 -0.5842)
			(stroke
				(width 0.1524)
				(type default)
			)
			(layer "B.SilkS")
		)
		(fp_line
			(start 1.2954 -0.5842)
			(end -1.2954 -0.5842)
			(stroke
				(width 0.1524)
				(type default)
			)
			(layer "B.SilkS")
		)
		(fp_line
			(start -1.2954 0.5842)
			(end 1.2954 0.5842)
			(stroke
				(width 0.1524)
				(type default)
			)
			(layer "B.SilkS")
		)
		(fp_line
			(start -1.2954 -0.5842)
			(end -1.2954 0.5842)
			(stroke
				(width 0.1524)
				(type default)
			)
			(layer "B.SilkS")
		)
		(fp_line
			(start 1.1938 0.4064)
			(end 1.1938 -0.406654)
			(stroke
				(width 0.1)
				(type default)
			)
			(layer "B.Fab")
		)
		(fp_line
			(start 1.1938 -0.406654)
			(end 0.8636 -0.406654)
			(stroke
				(width 0.1)
				(type default)
			)
			(layer "B.Fab")
		)
		(fp_line
			(start 0.8636 0.4572)
			(end 0.8636 0.4318)
			(stroke
				(width 0.1)
				(type default)
			)
			(layer "B.Fab")
		)
		(fp_line
			(start 0.8636 0.4318)
			(end 0.8636 0.4064)
			(stroke
				(width 0.1)
				(type default)
			)
			(layer "B.Fab")
		)
		(fp_line
			(start 0.8636 0.4064)
			(end 1.1938 0.4064)
			(stroke
				(width 0.1)
				(type default)
			)
			(layer "B.Fab")
		)
		(fp_line
			(start 0.8636 -0.406654)
			(end 0.8636 -0.4572)
			(stroke
				(width 0.1)
				(type default)
			)
			(layer "B.Fab")
		)
		(fp_line
			(start 0.8636 -0.4572)
			(end -0.8636 -0.4572)
			(stroke
				(width 0.1)
				(type default)
			)
			(layer "B.Fab")
		)
		(fp_line
			(start -0.8636 0.4572)
			(end 0.8636 0.4572)
			(stroke
				(width 0.1)
				(type default)
			)
			(layer "B.Fab")
		)
		(fp_line
			(start -0.8636 0.4064)
			(end -0.8636 0.4572)
			(stroke
				(width 0.1)
				(type default)
			)
			(layer "B.Fab")
		)
		(fp_line
			(start -0.8636 -0.406654)
			(end -1.1938 -0.406654)
			(stroke
				(width 0.1)
				(type default)
			)
			(layer "B.Fab")
		)
		(fp_line
			(start -0.8636 -0.4572)
			(end -0.8636 -0.406654)
			(stroke
				(width 0.1)
				(type default)
			)
			(layer "B.Fab")
		)
		(fp_line
			(start -1.1938 0.4064)
			(end -0.8636 0.4064)
			(stroke
				(width 0.1)
				(type default)
			)
			(layer "B.Fab")
		)
		(fp_line
			(start -1.1938 -0.406654)
			(end -1.1938 0.4064)
			(stroke
				(width 0.1)
				(type default)
			)
			(layer "B.Fab")
		)
		(pad "1" smd rect
			(at 0.7366 0 90)
			(size 0.7112 0.8128)
			(layers "B.Cu" "B.Mask" "B.Paste")
			(net "P0V9_CPU0_RT1_2A_2D")
		)
		(pad "2" smd rect
			(at -0.7366 0 90)
			(size 0.7112 0.8128)
			(layers "B.Cu" "B.Mask" "B.Paste")
			(net "P0V9_CPU0_RT1_2A")
		)
	)
	(footprint ""
		(layer "B.Cu")
		(at 362.407454 -268.41831)
		(property "Reference" "C2248"
			(at 0 0 0)
			(layer "B.SilkS")
			(hide yes)
			(effects
				(font
					(size 1.27 1.27)
				)
				(justify mirror)
			)
		)
		(property "Value" ""
			(at 0 0 0)
			(layer "B.Fab")
			(effects
				(font
					(size 1.27 1.27)
				)
				(justify mirror)
			)
		)
		(duplicate_pad_numbers_are_jumpers no)
		(fp_line
			(start -0.7874 -0.4064)
			(end -0.7874 0.4064)
			(stroke
				(width 0.1524)
				(type default)
			)
			(layer "B.SilkS")
		)
		(fp_line
			(start -0.7874 0.4064)
			(end 0.7874 0.4064)
			(stroke
				(width 0.1524)
				(type default)
			)
			(layer "B.SilkS")
		)
		(fp_line
			(start 0.7874 -0.4064)
			(end -0.7874 -0.4064)
			(stroke
				(width 0.1524)
				(type default)
			)
			(layer "B.SilkS")
		)
		(fp_line
			(start 0.7874 0.4064)
			(end 0.7874 -0.4064)
			(stroke
				(width 0.1524)
				(type default)
			)
			(layer "B.SilkS")
		)
		(fp_line
			(start -0.67945 -0.3048)
			(end -0.67945 0.3048)
			(stroke
				(width 0.1)
				(type default)
			)
			(layer "B.Fab")
		)
		(fp_line
			(start -0.67945 0.3048)
			(end -0.120396 0.3048)
			(stroke
				(width 0.1)
				(type default)
			)
			(layer "B.Fab")
		)
		(fp_line
			(start -0.12065 -0.3048)
			(end -0.67945 -0.3048)
			(stroke
				(width 0.1)
				(type default)
			)
			(layer "B.Fab")
		)
		(fp_line
			(start -0.12065 -0.2794)
			(end -0.12065 -0.3048)
			(stroke
				(width 0.1)
				(type default)
			)
			(layer "B.Fab")
		)
		(fp_line
			(start -0.120396 0.2794)
			(end 0.12065 0.2794)
			(stroke
				(width 0.1)
				(type default)
			)
			(layer "B.Fab")
		)
		(fp_line
			(start -0.120396 0.3048)
			(end -0.120396 0.2794)
			(stroke
				(width 0.1)
				(type default)
			)
			(layer "B.Fab")
		)
		(fp_line
			(start 0.12065 -0.305054)
			(end 0.12065 -0.2794)
			(stroke
				(width 0.1)
				(type default)
			)
			(layer "B.Fab")
		)
		(fp_line
			(start 0.12065 -0.2794)
			(end -0.12065 -0.2794)
			(stroke
				(width 0.1)
				(type default)
			)
			(layer "B.Fab")
		)
		(fp_line
			(start 0.12065 0.2794)
			(end 0.12065 0.3048)
			(stroke
				(width 0.1)
				(type default)
			)
			(layer "B.Fab")
		)
		(fp_line
			(start 0.12065 0.3048)
			(end 0.67945 0.3048)
			(stroke
				(width 0.1)
				(type default)
			)
			(layer "B.Fab")
		)
		(fp_line
			(start 0.67945 -0.305054)
			(end 0.12065 -0.305054)
			(stroke
				(width 0.1)
				(type default)
			)
			(layer "B.Fab")
		)
		(fp_line
			(start 0.67945 0.3048)
			(end 0.67945 -0.305054)
			(stroke
				(width 0.1)
				(type default)
			)
			(layer "B.Fab")
		)
		(pad "1" smd circle
			(at 0.40005 0 180)
			(size 0 0)
			(layers "B.Cu" "B.Mask" "B.Paste")
			(net "PVDDCR_CPU1_P0")
		)
		(pad "2" smd circle
			(at -0.40005 0 180)
			(size 0 0)
			(layers "B.Cu" "B.Mask" "B.Paste")
			(net "GND")
		)
	)
	(footprint ""
		(layer "B.Cu")
		(at 111.781336 -252.416564 180)
		(property "Reference" "C2268"
			(at 0 0 0)
			(layer "B.SilkS")
			(hide yes)
			(effects
				(font
					(size 1.27 1.27)
				)
				(justify mirror)
			)
		)
		(property "Value" ""
			(at 0 0 0)
			(layer "B.Fab")
			(effects
				(font
					(size 1.27 1.27)
				)
				(justify mirror)
			)
		)
		(duplicate_pad_numbers_are_jumpers no)
		(fp_line
			(start 0.7874 0.4064)
			(end 0.7874 -0.4064)
			(stroke
				(width 0.1524)
				(type default)
			)
			(layer "B.SilkS")
		)
		(fp_line
			(start 0.7874 -0.4064)
			(end -0.7874 -0.4064)
			(stroke
				(width 0.1524)
				(type default)
			)
			(layer "B.SilkS")
		)
		(fp_line
			(start -0.7874 0.4064)
			(end 0.7874 0.4064)
			(stroke
				(width 0.1524)
				(type default)
			)
			(layer "B.SilkS")
		)
		(fp_line
			(start -0.7874 -0.4064)
			(end -0.7874 0.4064)
			(stroke
				(width 0.1524)
				(type default)
			)
			(layer "B.SilkS")
		)
		(fp_line
			(start 0.67945 0.3048)
			(end 0.67945 -0.305054)
			(stroke
				(width 0.1)
				(type default)
			)
			(layer "B.Fab")
		)
		(fp_line
			(start 0.67945 -0.305054)
			(end 0.12065 -0.305054)
			(stroke
				(width 0.1)
				(type default)
			)
			(layer "B.Fab")
		)
		(fp_line
			(start 0.12065 0.3048)
			(end 0.67945 0.3048)
			(stroke
				(width 0.1)
				(type default)
			)
			(layer "B.Fab")
		)
		(fp_line
			(start 0.12065 0.2794)
			(end 0.12065 0.3048)
			(stroke
				(width 0.1)
				(type default)
			)
			(layer "B.Fab")
		)
		(fp_line
			(start 0.12065 -0.2794)
			(end -0.12065 -0.2794)
			(stroke
				(width 0.1)
				(type default)
			)
			(layer "B.Fab")
		)
		(fp_line
			(start 0.12065 -0.305054)
			(end 0.12065 -0.2794)
			(stroke
				(width 0.1)
				(type default)
			)
			(layer "B.Fab")
		)
		(fp_line
			(start -0.120396 0.3048)
			(end -0.120396 0.2794)
			(stroke
				(width 0.1)
				(type default)
			)
			(layer "B.Fab")
		)
		(fp_line
			(start -0.120396 0.2794)
			(end 0.12065 0.2794)
			(stroke
				(width 0.1)
				(type default)
			)
			(layer "B.Fab")
		)
		(fp_line
			(start -0.12065 -0.2794)
			(end -0.12065 -0.3048)
			(stroke
				(width 0.1)
				(type default)
			)
			(layer "B.Fab")
		)
		(fp_line
			(start -0.12065 -0.3048)
			(end -0.67945 -0.3048)
			(stroke
				(width 0.1)
				(type default)
			)
			(layer "B.Fab")
		)
		(fp_line
			(start -0.67945 0.3048)
			(end -0.120396 0.3048)
			(stroke
				(width 0.1)
				(type default)
			)
			(layer "B.Fab")
		)
		(fp_line
			(start -0.67945 -0.3048)
			(end -0.67945 0.3048)
			(stroke
				(width 0.1)
				(type default)
			)
			(layer "B.Fab")
		)
		(pad "1" smd circle
			(at 0.40005 0)
			(size 0 0)
			(layers "B.Cu" "B.Mask" "B.Paste")
			(net "PVDDCR_SOC_P1")
		)
		(pad "2" smd circle
			(at -0.40005 0)
			(size 0 0)
			(layers "B.Cu" "B.Mask" "B.Paste")
			(net "GND")
		)
	)
	(footprint ""
		(layer "B.Cu")
		(at 330.720446 -416.899344 90)
		(property "Reference" "C6549"
			(at 0 0 90)
			(layer "B.SilkS")
			(hide yes)
			(effects
				(font
					(size 1.27 1.27)
				)
				(justify mirror)
			)
		)
		(property "Value" ""
			(at 0 0 90)
			(layer "B.Fab")
			(effects
				(font
					(size 1.27 1.27)
				)
				(justify mirror)
			)
		)
		(duplicate_pad_numbers_are_jumpers no)
		(fp_line
			(start 0.299974 -0.150114)
			(end -0.299974 -0.150114)
			(stroke
				(width 0.1)
				(type default)
			)
			(layer "B.Fab")
		)
		(fp_line
			(start -0.299974 -0.150114)
			(end -0.299974 0.150114)
			(stroke
				(width 0.1)
				(type default)
			)
			(layer "B.Fab")
		)
		(fp_line
			(start 0.299974 0.150114)
			(end 0.299974 -0.150114)
			(stroke
				(width 0.1)
				(type default)
			)
			(layer "B.Fab")
		)
		(fp_line
			(start -0.299974 0.150114)
			(end 0.299974 0.150114)
			(stroke
				(width 0.1)
				(type default)
			)
			(layer "B.Fab")
		)
		(pad "1" smd rect
			(at 0.2667 0 270)
			(size 0.3048 0.381)
			(layers "B.Cu" "B.Mask" "B.Paste")
			(net "P5E_CPU0_P1_TX_BUF_C_DP<8>")
		)
		(pad "2" smd rect
			(at -0.2667 0 270)
			(size 0.3048 0.381)
			(layers "B.Cu" "B.Mask" "B.Paste")
			(net "P5E_CPU0_P1_TX_BUF_DP<8>")
		)
	)
)
